# S9S_MB_2U (Grand Teton) — schematic netlist excerpt (pin names and nets, part order shuffled) for the footprints in the layout excerpt that follows; sources: Cadence DE-HDL packaged netlist, KiCad conversion of 03242023_DA0F0TMBIJ0_F0T_Motherboard_J_brd_V01_OCP.brd

C1031  Q_CAP  22UF 4V 20% X6S  pkg C0402  page 74 : A = PVCCIN_CPU0 ; B = GND
R4406  Q_RES  4.75K 1% CHIP  pkg 0402LF  page 122 : A = P3V3 ; B = H_CPU1_MEMHOT_OUT_VT_N
C864  Q_CAP_DIFFBUS  DIFF BUS_0.22UF 6.3V 20% X6S  pkg C0201  page 174 : \1\ = P5E_CPU0_PE1_TX_C_DN<2> ; \2\ = P5E_CPU0_PE1_TX_DN<2>

(kicad_pcb
	(version 20260206)
	(generator "pcbnew")
	(generator_version "10.0")
	(general
		(thickness 1.6)
		(legacy_teardrops no)
	)
	(paper "A4")
	(title_block
		(title "03242023_DA0F0TMBIJ0_F0T_Motherboard_J_brd_V01_OCP.brd")
		(comment 1 "Grand Teton / footprints 1630-1632 of 6105")
	)
	(layers
		(0 "F.Cu" signal "TOP")
		(4 "In1.Cu" signal "GND")
		(6 "In2.Cu" signal "IN1")
		(8 "In3.Cu" signal "GND1")
		(10 "In4.Cu" signal "IN2")
		(12 "In5.Cu" signal "GND2")
		(14 "In6.Cu" signal "IN3")
		(16 "In7.Cu" signal "GND3")
		(18 "In8.Cu" signal "VCC")
		(20 "In9.Cu" signal "VCC1")
		(22 "In10.Cu" signal "GND4")
		(24 "In11.Cu" signal "IN4")
		(26 "In12.Cu" signal "GND5")
		(28 "In13.Cu" signal "IN5")
		(30 "In14.Cu" signal "GND6")
		(32 "In15.Cu" signal "IN6")
		(34 "In16.Cu" signal "GND7")
		(2 "B.Cu" signal "BOTTOM")
		(9 "F.Adhes" user "F.Adhesive")
		(11 "B.Adhes" user "B.Adhesive")
		(13 "F.Paste" user "Package Geometry/Pastemask Top")
		(15 "B.Paste" user "Package Geometry/Pastemask Bottom")
		(5 "F.SilkS" user "Ref Des/Silkscreen Top")
		(7 "B.SilkS" user "Ref Des/Silkscreen Bottom")
		(1 "F.Mask" user "Board Geometry/Soldermask Top")
		(3 "B.Mask" user "Board Geometry/Soldermask Bottom")
		(17 "Dwgs.User" user "User.Drawings")
		(19 "Cmts.User" user "User.Comments")
		(21 "Eco1.User" user "User.Eco1")
		(23 "Eco2.User" user "User.Eco2")
		(25 "Edge.Cuts" user "Board Geometry/Outline")
		(27 "Margin" user)
		(31 "F.CrtYd" user "Package Geometry/Place Bound Top")
		(29 "B.CrtYd" user "Package Geometry/Place Bound Bottom")
		(35 "F.Fab" user "Ref Des/Assembly Top")
		(33 "B.Fab" user "Ref Des/Assembly Bottom")
	)
	(footprint ""
		(layer "F.Cu")
		(at 136.07288 -92.674948 90)
		(property "Reference" "R4406"
			(at 0 0 90)
			(layer "F.SilkS")
			(hide yes)
			(effects
				(font
					(size 1.27 1.27)
				)
			)
		)
		(property "Value" ""
			(at 0 0 90)
			(layer "F.Fab")
			(effects
				(font
					(size 1.27 1.27)
				)
			)
		)
		(duplicate_pad_numbers_are_jumpers no)
		(fp_line
			(start 0.7874 -0.4064)
			(end 0.7874 0.4064)
			(stroke
				(width 0.1524)
				(type default)
			)
			(layer "F.SilkS")
		)
		(fp_line
			(start -0.7874 -0.4064)
			(end 0.7874 -0.4064)
			(stroke
				(width 0.1524)
				(type default)
			)
			(layer "F.SilkS")
		)
		(fp_line
			(start 0.7874 0.4064)
			(end -0.7874 0.4064)
			(stroke
				(width 0.1524)
				(type default)
			)
			(layer "F.SilkS")
		)
		(fp_line
			(start -0.7874 0.4064)
			(end -0.7874 -0.4064)
			(stroke
				(width 0.1524)
				(type default)
			)
			(layer "F.SilkS")
		)
		(fp_line
			(start -0.12065 -0.305054)
			(end -0.12065 -0.2794)
			(stroke
				(width 0.1)
				(type default)
			)
			(layer "F.Fab")
		)
		(fp_line
			(start -0.67945 -0.305054)
			(end -0.12065 -0.305054)
			(stroke
				(width 0.1)
				(type default)
			)
			(layer "F.Fab")
		)
		(fp_line
			(start 0.67945 -0.3048)
			(end 0.67945 0.3048)
			(stroke
				(width 0.1)
				(type default)
			)
			(layer "F.Fab")
		)
		(fp_line
			(start 0.12065 -0.3048)
			(end 0.67945 -0.3048)
			(stroke
				(width 0.1)
				(type default)
			)
			(layer "F.Fab")
		)
		(fp_line
			(start 0.12065 -0.2794)
			(end 0.12065 -0.3048)
			(stroke
				(width 0.1)
				(type default)
			)
			(layer "F.Fab")
		)
		(fp_line
			(start -0.12065 -0.2794)
			(end 0.12065 -0.2794)
			(stroke
				(width 0.1)
				(type default)
			)
			(layer "F.Fab")
		)
		(fp_line
			(start 0.120396 0.2794)
			(end -0.12065 0.2794)
			(stroke
				(width 0.1)
				(type default)
			)
			(layer "F.Fab")
		)
		(fp_line
			(start -0.12065 0.2794)
			(end -0.12065 0.3048)
			(stroke
				(width 0.1)
				(type default)
			)
			(layer "F.Fab")
		)
		(fp_line
			(start 0.67945 0.3048)
			(end 0.120396 0.3048)
			(stroke
				(width 0.1)
				(type default)
			)
			(layer "F.Fab")
		)
		(fp_line
			(start 0.120396 0.3048)
			(end 0.120396 0.2794)
			(stroke
				(width 0.1)
				(type default)
			)
			(layer "F.Fab")
		)
		(fp_line
			(start -0.12065 0.3048)
			(end -0.67945 0.3048)
			(stroke
				(width 0.1)
				(type default)
			)
			(layer "F.Fab")
		)
		(fp_line
			(start -0.67945 0.3048)
			(end -0.67945 -0.305054)
			(stroke
				(width 0.1)
				(type default)
			)
			(layer "F.Fab")
		)
		(pad "1" smd circle
			(at -0.40005 0 90)
			(size 0 0)
			(layers "F.Cu" "F.Mask" "F.Paste")
			(net "P3V3")
		)
		(pad "2" smd circle
			(at 0.40005 0 90)
			(size 0 0)
			(layers "F.Cu" "F.Mask" "F.Paste")
			(net "H_CPU1_MEMHOT_OUT_VT_N")
		)
	)
	(footprint ""
		(layer "F.Cu")
		(at 426.677836 -17.612614 90)
		(property "Reference" "C864"
			(at 0 0 90)
			(layer "F.SilkS")
			(hide yes)
			(effects
				(font
					(size 1.27 1.27)
				)
			)
		)
		(property "Value" ""
			(at 0 0 90)
			(layer "F.Fab")
			(effects
				(font
					(size 1.27 1.27)
				)
			)
		)
		(duplicate_pad_numbers_are_jumpers no)
		(fp_line
			(start 0.299974 -0.150114)
			(end 0.299974 0.150114)
			(stroke
				(width 0.1)
				(type default)
			)
			(layer "F.Fab")
		)
		(fp_line
			(start -0.299974 -0.150114)
			(end 0.299974 -0.150114)
			(stroke
				(width 0.1)
				(type default)
			)
			(layer "F.Fab")
		)
		(fp_line
			(start 0.299974 0.150114)
			(end -0.299974 0.150114)
			(stroke
				(width 0.1)
				(type default)
			)
			(layer "F.Fab")
		)
		(fp_line
			(start -0.299974 0.150114)
			(end -0.299974 -0.150114)
			(stroke
				(width 0.1)
				(type default)
			)
			(layer "F.Fab")
		)
		(pad "1" smd rect
			(at -0.2667 0 90)
			(size 0.3048 0.381)
			(layers "F.Cu" "F.Mask" "F.Paste")
			(net "P5E_CPU0_PE1_TX_C_DN<2>")
		)
		(pad "2" smd rect
			(at 0.2667 0 90)
			(size 0.3048 0.381)
			(layers "F.Cu" "F.Mask" "F.Paste")
			(net "P5E_CPU0_PE1_TX_DN<2>")
		)
	)
	(footprint ""
		(layer "F.Cu")
		(at 354.262944 -240.276888 90)
		(property "Reference" "C1031"
			(at 0 0 90)
			(layer "F.SilkS")
			(hide yes)
			(effects
				(font
					(size 1.27 1.27)
				)
			)
		)
		(property "Value" ""
			(at 0 0 90)
			(layer "F.Fab")
			(effects
				(font
					(size 1.27 1.27)
				)
			)
		)
		(duplicate_pad_numbers_are_jumpers no)
		(fp_line
			(start 0.7874 -0.4064)
			(end 0.7874 0.4064)
			(stroke
				(width 0.1524)
				(type default)
			)
			(layer "F.SilkS")
		)
		(fp_line
			(start -0.7874 -0.4064)
			(end 0.7874 -0.4064)
			(stroke
				(width 0.1524)
				(type default)
			)
			(layer "F.SilkS")
		)
		(fp_line
			(start 0.7874 0.4064)
			(end -0.7874 0.4064)
			(stroke
				(width 0.1524)
				(type default)
			)
			(layer "F.SilkS")
		)
		(fp_line
			(start -0.7874 0.4064)
			(end -0.7874 -0.4064)
			(stroke
				(width 0.1524)
				(type default)
			)
			(layer "F.SilkS")
		)
		(fp_line
			(start -0.12065 -0.305054)
			(end -0.12065 -0.2794)
			(stroke
				(width 0.1)
				(type default)
			)
			(layer "F.Fab")
		)
		(fp_line
			(start -0.67945 -0.305054)
			(end -0.12065 -0.305054)
			(stroke
				(width 0.1)
				(type default)
			)
			(layer "F.Fab")
		)
		(fp_line
			(start 0.67945 -0.3048)
			(end 0.67945 0.3048)
			(stroke
				(width 0.1)
				(type default)
			)
			(layer "F.Fab")
		)
		(fp_line
			(start 0.12065 -0.3048)
			(end 0.67945 -0.3048)
			(stroke
				(width 0.1)
				(type default)
			)
			(layer "F.Fab")
		)
		(fp_line
			(start 0.12065 -0.2794)
			(end 0.12065 -0.3048)
			(stroke
				(width 0.1)
				(type default)
			)
			(layer "F.Fab")
		)
		(fp_line
			(start -0.12065 -0.2794)
			(end 0.12065 -0.2794)
			(stroke
				(width 0.1)
				(type default)
			)
			(layer "F.Fab")
		)
		(fp_line
			(start 0.120396 0.2794)
			(end -0.12065 0.2794)
			(stroke
				(width 0.1)
				(type default)
			)
			(layer "F.Fab")
		)
		(fp_line
			(start -0.12065 0.2794)
			(end -0.12065 0.3048)
			(stroke
				(width 0.1)
				(type default)
			)
			(layer "F.Fab")
		)
		(fp_line
			(start 0.67945 0.3048)
			(end 0.120396 0.3048)
			(stroke
				(width 0.1)
				(type default)
			)
			(layer "F.Fab")
		)
		(fp_line
			(start 0.120396 0.3048)
			(end 0.120396 0.2794)
			(stroke
				(width 0.1)
				(type default)
			)
			(layer "F.Fab")
		)
		(fp_line
			(start -0.12065 0.3048)
			(end -0.67945 0.3048)
			(stroke
				(width 0.1)
				(type default)
			)
			(layer "F.Fab")
		)
		(fp_line
			(start -0.67945 0.3048)
			(end -0.67945 -0.305054)
			(stroke
				(width 0.1)
				(type default)
			)
			(layer "F.Fab")
		)
		(pad "1" smd circle
			(at -0.40005 0 90)
			(size 0 0)
			(layers "F.Cu" "F.Mask" "F.Paste")
			(net "PVCCIN_CPU0")
		)
		(pad "2" smd circle
			(at 0.40005 0 90)
			(size 0 0)
			(layers "F.Cu" "F.Mask" "F.Paste")
			(net "GND")
		)
	)
)
